# T6G (Grand Teton) — schematic netlist excerpt (pin names and nets, part order shuffled) for the footprints in the layout excerpt that follows; sources: Cadence DE-HDL packaged netlist, KiCad conversion of 04192023_DAF0TMB3IC0_F0TG_MB_C_brd_V02_OCP.brd

J24  SCONN288_DDR506112002KQ  IO  pkg DDR288S_1-1VXC  page 98
  VIN_BULK0  = P12V_MEM_CPU1
  RFU0  = NC
  VIN_MGMT  = P3V3_AUX
  HSCL  = I3C_SPD_DDRA_CPU1_SCL
  HSDA  = I3C_SPD_DDRA_CPU1_SDA
  VSS0  = GND
  DQ0_A  = M_A_CPU1_SA_DQ<0>
  VSS1  = GND
  DQ1_A  = M_A_CPU1_SA_DQ<1>
  VSS2  = GND
  DQS0_A_T  = M_A_CPU1_SA_DQS_DP<0>
  DQS0_A_C  = M_A_CPU1_SA_DQS_DN<0>
  VSS3  = GND
  DQ4_A  = M_A_CPU1_SA_DQ<4>
  VSS4  = GND
  DQ5_A  = M_A_CPU1_SA_DQ<5>
  VSS5  = GND
  DQ8_A  = M_A_CPU1_SA_DQ<8>
  VSS6  = GND
  DQ9_A  = M_A_CPU1_SA_DQ<9>
  VSS7  = GND
  DQS1_A_T  = M_A_CPU1_SA_DQS_DP<1>
  DQS1_A_C  = M_A_CPU1_SA_DQS_DN<1>
  VSS8  = GND
  DQ12_A  = M_A_CPU1_SA_DQ<12>
  VSS9  = GND
  DQ13_A  = M_A_CPU1_SA_DQ<13>
  VSS10  = GND
  DQ16_A  = M_A_CPU1_SA_DQ<16>
  VSS11  = GND
  DQ17_A  = M_A_CPU1_SA_DQ<17>
  VSS12  = GND
  DQS2_A_T  = M_A_CPU1_SA_DQS_DP<2>
  DQS2_A_C  = M_A_CPU1_SA_DQS_DN<2>
  VSS13  = GND
  DQ20_A  = M_A_CPU1_SA_DQ<20>
  VSS14  = GND
  DQ21_A  = M_A_CPU1_SA_DQ<21>
  VSS15  = GND
  DQ24_A  = M_A_CPU1_SA_DQ<24>
  VSS16  = GND
  DQ25_A  = M_A_CPU1_SA_DQ<25>
  VSS17  = GND
  DQS3_A_T  = M_A_CPU1_SA_DQS_DP<3>
  DQS3_A_C  = M_A_CPU1_SA_DQS_DN<3>
  VSS18  = GND
  DQ28_A  = M_A_CPU1_SA_DQ<28>
  VSS19  = GND
  DQ29_A  = M_A_CPU1_SA_DQ<29>
  VSS20  = GND
  CB0_A  = M_A_CPU1_SA_CB<0>
  VSS21  = GND
  CB1_A  = M_A_CPU1_SA_CB<1>
  VSS22  = GND
  DQS4_A_T  = M_A_CPU1_SA_DQS_DP<4>
  DQS4_A_C  = M_A_CPU1_SA_DQS_DN<4>
  VSS23  = GND
  CB4_A  = M_A_CPU1_SA_CB<4>
  VSS24  = GND
  CB5_A  = M_A_CPU1_SA_CB<5>
  VSS25  = GND
  ALERT_N  = M_A_CPU1_ALERT_N
  VSS26  = GND
  CS0_A_N  = M_A_CPU1_SA_CS_N<0>
  VSS27  = GND
  CA0_A  = M_A_CPU1_SA_CA<0>
  VSS28  = GND
  CA2_A  = M_A_CPU1_SA_CA<2>
  VSS29  = GND
  CA4_A  = M_A_CPU1_SA_CA<4>
  VSS30  = GND
  CA6_A  = M_A_CPU1_SA_CA<6>
  VSS31  = GND
  PAR_A  = M_A_CPU1_SA_PAR
  VSS32  = GND
  CA0_B  = M_A_CPU1_SB_CA<0>
  VSS33  = GND
  CA2_B  = M_A_CPU1_SB_CA<2>
  VSS34  = GND
  CA4_B  = M_A_CPU1_SB_CA<4>
  VSS35  = GND
  CA6_B  = M_A_CPU1_SB_CA<6>
  VSS36  = GND
  CS0_B_N  = M_A_CPU1_SB_CS_N<0>
  VSS37  = GND
  \lbd||rsp_a_n\  = M_A_CPU1_SA_RSP<0>
  \lbs||rsp_b_n\  = M_A_CPU1_SB_RSP<0>
  VSS38  = GND
  CB4_B  = M_A_CPU1_SB_CB<4>
  VSS39  = GND
  CB5_B  = M_A_CPU1_SB_CB<5>
  VSS40  = GND
  \dqs9_b_t||tdqs9_b_t||dbi4_b_n\  = M_A_CPU1_SB_DQS_DP<9>
  \dqs9_b_c||tdqs9_b_c\  = M_A_CPU1_SB_DQS_DN<9>
  VSS41  = GND
  CB0_B  = M_A_CPU1_SB_CB<0>
  VSS42  = GND
  CB1_B  = M_A_CPU1_SB_CB<1>
  VSS43  = GND
  DQ0_B  = M_A_CPU1_SB_DQ<0>
  VSS44  = GND
  DQ1_B  = M_A_CPU1_SB_DQ<1>
  VSS45  = GND
  DQS0_B_T  = M_A_CPU1_SB_DQS_DP<0>
  DQS0_B_C  = M_A_CPU1_SB_DQS_DN<0>
  VSS46  = GND
  DQ4_B  = M_A_CPU1_SB_DQ<4>
  VSS47  = GND
  DQ5_B  = M_A_CPU1_SB_DQ<5>
  VSS48  = GND
  DQ8_B  = M_A_CPU1_SB_DQ<8>
  VSS49  = GND
  DQ9_B  = M_A_CPU1_SB_DQ<9>
  VSS50  = GND
  DQS1_B_T  = M_A_CPU1_SB_DQS_DP<1>
  DQS1_B_C  = M_A_CPU1_SB_DQS_DN<1>
  VSS51  = GND
  DQ12_B  = M_A_CPU1_SB_DQ<12>
  VSS52  = GND
  DQ13_B  = M_A_CPU1_SB_DQ<13>
  VSS53  = GND
  DQ16_B  = M_A_CPU1_SB_DQ<16>
  VSS54  = GND
  DQ17_B  = M_A_CPU1_SB_DQ<17>
  VSS55  = GND
  DQS2_B_T  = M_A_CPU1_SB_DQS_DP<2>
  DQS2_B_C  = M_A_CPU1_SB_DQS_DN<2>
  VSS56  = GND
  DQ20_B  = M_A_CPU1_SB_DQ<20>
  VSS57  = GND
  DQ21_B  = M_A_CPU1_SB_DQ<21>
  VSS58  = GND
  DQ24_B  = M_A_CPU1_SB_DQ<24>
  VSS59  = GND
  DQ25_B  = M_A_CPU1_SB_DQ<25>
  VSS60  = GND
  DQS3_B_T  = M_A_CPU1_SB_DQS_DP<3>
  DQS3_B_C  = M_A_CPU1_SB_DQS_DN<3>
  VSS61  = GND
  DQ28_B  = M_A_CPU1_SB_DQ<28>
  VSS62  = GND
  DQ29_B  = M_A_CPU1_SB_DQ<29>
  VSS63  = GND
  RFU1  = NC
  VIN_BULK1  = P12V_MEM_CPU1
  VIN_BULK2  = P12V_MEM_CPU1
  \pwr_good||fail_n\  = PWRGD_CHA_CPU1_DIMM0
  HAS  = PD_CHA_CPU1_DIMM0_SAA
  RFU2  = NC
  RFU3  = NC
  VSS64  = GND
  DQ2_A  = M_A_CPU1_SA_DQ<2>
  VSS65  = GND
  DQ3_A  = M_A_CPU1_SA_DQ<3>
  VSS66  = GND
  \dqs5_a_c||tdqs5_a_c||dqs5_a_t||tdqs5_a_t\  = M_A_CPU1_SA_DQS_DN<5>
  \dqs5_a_t||tdqs5_a_t\  = M_A_CPU1_SA_DQS_DP<5>
  VSS67  = GND
  DQ6_A  = M_A_CPU1_SA_DQ<6>
  VSS68  = GND
  DQ7_A  = M_A_CPU1_SA_DQ<7>
  VSS69  = GND
  DQ10_A  = M_A_CPU1_SA_DQ<10>
  VSS70  = GND
  DQ11_A  = M_A_CPU1_SA_DQ<11>
  VSS71  = GND
  \dqs6_a_c||tdqs6_a_c||dqs6_a_t||tdqs6_a_t\  = M_A_CPU1_SA_DQS_DN<6>
  \dqs6_a_t||tdqs6_a_t\  = M_A_CPU1_SA_DQS_DP<6>
  VSS72  = GND
  DQ14_A  = M_A_CPU1_SA_DQ<14>
  VSS73  = GND
  DQ15_A  = M_A_CPU1_SA_DQ<15>
  VSS74  = GND
  DQ18_A  = M_A_CPU1_SA_DQ<18>
  VSS75  = GND
  DQ19_A  = M_A_CPU1_SA_DQ<19>
  VSS76  = GND
  \dqs7_a_c||tdqs7_a_c\  = M_A_CPU1_SA_DQS_DN<7>
  \dqs7_a_t||tdqs7_a_t\  = M_A_CPU1_SA_DQS_DP<7>
  VSS77  = GND
  DQ22_A  = M_A_CPU1_SA_DQ<22>
  VSS78  = GND
  DQ23_A  = M_A_CPU1_SA_DQ<23>
  VSS79  = GND
  DQ26_A  = M_A_CPU1_SA_DQ<26>
  VSS80  = GND
  DQ27_A  = M_A_CPU1_SA_DQ<27>
  VSS81  = GND
  \dqs8_a_c||tdqs8_a_c\  = M_A_CPU1_SA_DQS_DN<8>
  \dqs8_a_t||tdqs8_a_t\  = M_A_CPU1_SA_DQS_DP<8>
  VSS82  = GND
  DQ30_A  = M_A_CPU1_SA_DQ<30>
  VSS83  = GND
  DQ31_A  = M_A_CPU1_SA_DQ<31>
  VSS84  = GND
  CB2_A  = M_A_CPU1_SA_CB<2>
  VSS85  = GND
  CB3_A  = M_A_CPU1_SA_CB<3>
  VSS86  = GND
  \dqs9_a_c||tdqs9_a_c\  = M_A_CPU1_SA_DQS_DN<9>
  \dqs9_a_t||tdqs9_a_t\  = M_A_CPU1_SA_DQS_DP<9>
  VSS87  = GND
  CB6_A  = M_A_CPU1_SA_CB<6>
  VSS88  = GND
  CB7_A  = M_A_CPU1_SA_CB<7>
  VSS89  = GND
  RESET_N  = M_A_CPU1_RESET_N
  VSS90  = GND
  CS1_A_N  = M_A_CPU1_SA_CS_N<1>
  VSS91  = GND
  CA1_A  = M_A_CPU1_SA_CA<1>
  VSS92  = GND
  CA3_A  = M_A_CPU1_SA_CA<3>
  VSS93  = GND
  CA5_A  = M_A_CPU1_SA_CA<5>
  VSS94  = GND
  CK_T  = M_A_CPU1_CLK_DP<0>
  CK_C  = M_A_CPU1_CLK_DN<0>
  VSS95  = GND
  RFU4  = NC
  CA1_B  = M_A_CPU1_SB_CA<1>
  VSS96  = GND
  CA3_B  = M_A_CPU1_SB_CA<3>
  VSS97  = GND
  CA5_B  = M_A_CPU1_SB_CA<5>
  VSS98  = GND
  PAR_B  = M_A_CPU1_SB_PAR
  VSS99  = GND
  CS1_B_N  = M_A_CPU1_SB_CS_N<1>
  VSS100  = GND
  RFU5  = NC
  RFU6  = NC
  VSS101  = GND
  CB6_B  = M_A_CPU1_SB_CB<6>
  VSS102  = GND
  CB7_B  = M_A_CPU1_SB_CB<7>
  VSS103  = GND
  DQS4_B_C  = M_A_CPU1_SB_DQS_DN<4>
  DQS4_B_T  = M_A_CPU1_SB_DQS_DP<4>
  VSS104  = GND
  CB2_B  = M_A_CPU1_SB_CB<2>
  VSS105  = GND
  CB3_B  = M_A_CPU1_SB_CB<3>
  VSS106  = GND
  DQ2_B  = M_A_CPU1_SB_DQ<2>
  VSS107  = GND
  DQ3_B  = M_A_CPU1_SB_DQ<3>
  VSS108  = GND
  \dqs5_b_c||tdqs5_b_c\  = M_A_CPU1_SB_DQS_DN<5>
  \dqs5_b_t||tdqs5_b_t\  = M_A_CPU1_SB_DQS_DP<5>
  VSS109  = GND
  DQ6_B  = M_A_CPU1_SB_DQ<6>
  VSS110  = GND
  DQ7_B  = M_A_CPU1_SB_DQ<7>
  VSS111  = GND
  DQ10_B  = M_A_CPU1_SB_DQ<10>
  VSS112  = GND
  DQ11_B  = M_A_CPU1_SB_DQ<11>
  VSS113  = GND
  \dqs6_b_c||tdqs6_b_c\  = M_A_CPU1_SB_DQS_DN<6>
  \dqs6_b_t||tdqs6_b_t\  = M_A_CPU1_SB_DQS_DP<6>
  VSS114  = GND
  DQ14_B  = M_A_CPU1_SB_DQ<14>
  VSS115  = GND
  DQ15_B  = M_A_CPU1_SB_DQ<15>
  VSS116  = GND
  DQ18_B  = M_A_CPU1_SB_DQ<18>
  VSS117  = GND
  DQ19_B  = M_A_CPU1_SB_DQ<19>
  VSS118  = GND
  \dqs7_b_c||tdqs7_b_c\  = M_A_CPU1_SB_DQS_DN<7>
  \dqs7_b_t||tdqs7_b_t\  = M_A_CPU1_SB_DQS_DP<7>
  VSS119  = GND
  DQ22_B  = M_A_CPU1_SB_DQ<22>
  VSS120  = GND
  DQ23_B  = M_A_CPU1_SB_DQ<23>
  VSS121  = GND
  DQ26_B  = M_A_CPU1_SB_DQ<26>
  VSS122  = GND
  DQ27_B  = M_A_CPU1_SB_DQ<27>
  VSS123  = GND
  \dqs8_b_c||tdqs8_b_c\  = M_A_CPU1_SB_DQS_DN<8>
  \dqs8_b_t||tdqs8_b_t\  = M_A_CPU1_SB_DQS_DP<8>
  VSS124  = GND
  DQ30_B  = M_A_CPU1_SB_DQ<30>
  VSS125  = GND
  DQ31_B  = M_A_CPU1_SB_DQ<31>
  VSS126  = GND
  G1  = GND
  G2  = GND
  G3  = GND

(kicad_pcb
	(version 20260206)
	(generator "pcbnew")
	(generator_version "10.0")
	(general
		(thickness 1.6)
		(legacy_teardrops no)
	)
	(paper "A4")
	(title_block
		(title "04192023_DAF0TMB3IC0_F0TG_MB_C_brd_V02_OCP.brd")
		(comment 1 "Grand Teton / footprint 2100 of 8354 (J24), pads 185-230 of 291")
	)
	(layers
		(0 "F.Cu" signal "TOP")
		(4 "In1.Cu" signal "GND")
		(6 "In2.Cu" signal "IN1")
		(8 "In3.Cu" signal "GND1")
		(10 "In4.Cu" signal "IN2")
		(12 "In5.Cu" signal "GND2")
		(14 "In6.Cu" signal "IN3")
		(16 "In7.Cu" signal "GND3")
		(18 "In8.Cu" signal "VCC")
		(20 "In9.Cu" signal "VCC1")
		(22 "In10.Cu" signal "GND4")
		(24 "In11.Cu" signal "IN4")
		(26 "In12.Cu" signal "GND5")
		(28 "In13.Cu" signal "IN5")
		(30 "In14.Cu" signal "GND6")
		(32 "In15.Cu" signal "IN6")
		(34 "In16.Cu" signal "GND7")
		(2 "B.Cu" signal "BOTTOM")
		(9 "F.Adhes" user "F.Adhesive")
		(11 "B.Adhes" user "B.Adhesive")
		(13 "F.Paste" user "Package Geometry/Pastemask Top")
		(15 "B.Paste" user "Package Geometry/Pastemask Bottom")
		(5 "F.SilkS" user "Ref Des/Silkscreen Top")
		(7 "B.SilkS" user "Ref Des/Silkscreen Bottom")
		(1 "F.Mask" user "Board Geometry/Soldermask Top")
		(3 "B.Mask" user "Board Geometry/Soldermask Bottom")
		(17 "Dwgs.User" user "User.Drawings")
		(19 "Cmts.User" user "User.Comments")
		(21 "Eco1.User" user "User.Eco1")
		(23 "Eco2.User" user "User.Eco2")
		(25 "Edge.Cuts" user "Board Geometry/Outline")
		(27 "Margin" user)
		(31 "F.CrtYd" user "Package Geometry/Place Bound Top")
		(29 "B.CrtYd" user "Package Geometry/Place Bound Bottom")
		(35 "F.Fab" user "Ref Des/Assembly Top")
		(33 "B.Fab" user "Ref Des/Assembly Bottom")
	)
	(footprint ""
		(layer "F.Cu")
		(at 57.378092 -255.560322 180)
		(property "Reference" "J24"
			(at 1.914906 -84.58708 0)
			(unlocked yes)
			(layer "F.SilkS")
			(effects
				(font
					(size 0.7874 0.5842)
					(thickness 0.1524)
				)
			)
		)
		(property "Value" ""
			(at 0 0 180)
			(layer "F.Fab")
			(effects
				(font
					(size 1.27 1.27)
				)
			)
		)
		(duplicate_pad_numbers_are_jumpers no)
		(pad "185" smd rect
			(at 2.050034 -29.325062 90)
			(size 0.519938 1.4986)
			(layers "F.Cu" "F.Mask" "F.Paste")
			(net "M_A_CPU1_SA_DQ<26>")
		)
		(pad "186" smd rect
			(at 2.050034 -28.474924 90)
			(size 0.519938 1.4986)
			(layers "F.Cu" "F.Mask" "F.Paste")
			(net "GND")
		)
		(pad "187" smd rect
			(at 2.050034 -27.62504 90)
			(size 0.519938 1.4986)
			(layers "F.Cu" "F.Mask" "F.Paste")
			(net "M_A_CPU1_SA_DQ<27>")
		)
		(pad "188" smd rect
			(at 2.050034 -26.774902 90)
			(size 0.519938 1.4986)
			(layers "F.Cu" "F.Mask" "F.Paste")
			(net "GND")
		)
		(pad "189" smd rect
			(at 2.050034 -25.925018 90)
			(size 0.519938 1.4986)
			(layers "F.Cu" "F.Mask" "F.Paste")
			(net "M_A_CPU1_SA_DQS_DN<8>")
		)
		(pad "190" smd rect
			(at 2.050034 -25.07488 90)
			(size 0.519938 1.4986)
			(layers "F.Cu" "F.Mask" "F.Paste")
			(net "M_A_CPU1_SA_DQS_DP<8>")
		)
		(pad "191" smd rect
			(at 2.050034 -24.224996 90)
			(size 0.519938 1.4986)
			(layers "F.Cu" "F.Mask" "F.Paste")
			(net "GND")
		)
		(pad "192" smd rect
			(at 2.050034 -23.375112 90)
			(size 0.519938 1.4986)
			(layers "F.Cu" "F.Mask" "F.Paste")
			(net "M_A_CPU1_SA_DQ<30>")
		)
		(pad "193" smd rect
			(at 2.050034 -22.524974 90)
			(size 0.519938 1.4986)
			(layers "F.Cu" "F.Mask" "F.Paste")
			(net "GND")
		)
		(pad "194" smd rect
			(at 2.050034 -21.67509 90)
			(size 0.519938 1.4986)
			(layers "F.Cu" "F.Mask" "F.Paste")
			(net "M_A_CPU1_SA_DQ<31>")
		)
		(pad "195" smd rect
			(at 2.050034 -20.824952 90)
			(size 0.519938 1.4986)
			(layers "F.Cu" "F.Mask" "F.Paste")
			(net "GND")
		)
		(pad "196" smd rect
			(at 2.050034 -19.975068 90)
			(size 0.519938 1.4986)
			(layers "F.Cu" "F.Mask" "F.Paste")
			(net "M_A_CPU1_SA_CB<2>")
		)
		(pad "197" smd rect
			(at 2.050034 -19.12493 90)
			(size 0.519938 1.4986)
			(layers "F.Cu" "F.Mask" "F.Paste")
			(net "GND")
		)
		(pad "198" smd rect
			(at 2.050034 -18.275046 90)
			(size 0.519938 1.4986)
			(layers "F.Cu" "F.Mask" "F.Paste")
			(net "M_A_CPU1_SA_CB<3>")
		)
		(pad "199" smd rect
			(at 2.050034 -17.424908 90)
			(size 0.519938 1.4986)
			(layers "F.Cu" "F.Mask" "F.Paste")
			(net "GND")
		)
		(pad "200" smd rect
			(at 2.050034 -16.575024 90)
			(size 0.519938 1.4986)
			(layers "F.Cu" "F.Mask" "F.Paste")
			(net "M_A_CPU1_SA_DQS_DN<9>")
		)
		(pad "201" smd rect
			(at 2.050034 -15.724886 90)
			(size 0.519938 1.4986)
			(layers "F.Cu" "F.Mask" "F.Paste")
			(net "M_A_CPU1_SA_DQS_DP<9>")
		)
		(pad "202" smd rect
			(at 2.050034 -14.875002 90)
			(size 0.519938 1.4986)
			(layers "F.Cu" "F.Mask" "F.Paste")
			(net "GND")
		)
		(pad "203" smd rect
			(at 2.050034 -14.025118 90)
			(size 0.519938 1.4986)
			(layers "F.Cu" "F.Mask" "F.Paste")
			(net "M_A_CPU1_SA_CB<6>")
		)
		(pad "204" smd rect
			(at 2.050034 -13.17498 90)
			(size 0.519938 1.4986)
			(layers "F.Cu" "F.Mask" "F.Paste")
			(net "GND")
		)
		(pad "205" smd rect
			(at 2.050034 -12.325096 90)
			(size 0.519938 1.4986)
			(layers "F.Cu" "F.Mask" "F.Paste")
			(net "M_A_CPU1_SA_CB<7>")
		)
		(pad "206" smd rect
			(at 2.050034 -11.474958 90)
			(size 0.519938 1.4986)
			(layers "F.Cu" "F.Mask" "F.Paste")
			(net "GND")
		)
		(pad "207" smd rect
			(at 2.050034 -10.625074 90)
			(size 0.519938 1.4986)
			(layers "F.Cu" "F.Mask" "F.Paste")
			(net "M_A_CPU1_RESET_N")
		)
		(pad "208" smd rect
			(at 2.050034 -9.774936 90)
			(size 0.519938 1.4986)
			(layers "F.Cu" "F.Mask" "F.Paste")
			(net "GND")
		)
		(pad "209" smd rect
			(at 2.050034 -8.925052 90)
			(size 0.519938 1.4986)
			(layers "F.Cu" "F.Mask" "F.Paste")
			(net "M_A_CPU1_SA_CS_N<1>")
		)
		(pad "210" smd rect
			(at 2.050034 -8.074914 90)
			(size 0.519938 1.4986)
			(layers "F.Cu" "F.Mask" "F.Paste")
			(net "GND")
		)
		(pad "211" smd rect
			(at 2.050034 -7.22503 90)
			(size 0.519938 1.4986)
			(layers "F.Cu" "F.Mask" "F.Paste")
			(net "M_A_CPU1_SA_CA<1>")
		)
		(pad "212" smd rect
			(at 2.050034 -6.374892 90)
			(size 0.519938 1.4986)
			(layers "F.Cu" "F.Mask" "F.Paste")
			(net "GND")
		)
		(pad "213" smd rect
			(at 2.050034 -5.525008 90)
			(size 0.519938 1.4986)
			(layers "F.Cu" "F.Mask" "F.Paste")
			(net "M_A_CPU1_SA_CA<3>")
		)
		(pad "214" smd rect
			(at 2.050034 -4.675124 90)
			(size 0.519938 1.4986)
			(layers "F.Cu" "F.Mask" "F.Paste")
			(net "GND")
		)
		(pad "215" smd rect
			(at 2.050034 -3.824986 90)
			(size 0.519938 1.4986)
			(layers "F.Cu" "F.Mask" "F.Paste")
			(net "M_A_CPU1_SA_CA<5>")
		)
		(pad "216" smd rect
			(at 2.050034 -2.975102 90)
			(size 0.519938 1.4986)
			(layers "F.Cu" "F.Mask" "F.Paste")
			(net "GND")
		)
		(pad "217" smd rect
			(at 2.050034 -2.124964 90)
			(size 0.519938 1.4986)
			(layers "F.Cu" "F.Mask" "F.Paste")
			(net "M_A_CPU1_CLK_DP<0>")
		)
		(pad "218" smd rect
			(at 2.050034 -1.27508 90)
			(size 0.519938 1.4986)
			(layers "F.Cu" "F.Mask" "F.Paste")
			(net "M_A_CPU1_CLK_DN<0>")
		)
		(pad "219" smd rect
			(at 2.050034 -0.424942 90)
			(size 0.519938 1.4986)
			(layers "F.Cu" "F.Mask" "F.Paste")
			(net "GND")
		)
		(pad "220" smd rect
			(at 2.050034 5.525008 90)
			(size 0.519938 1.4986)
			(layers "F.Cu" "F.Mask" "F.Paste")
			(net "Net_2260")
		)
		(pad "221" smd rect
			(at 2.050034 6.374892 90)
			(size 0.519938 1.4986)
			(layers "F.Cu" "F.Mask" "F.Paste")
			(net "M_A_CPU1_SB_CA<1>")
		)
		(pad "222" smd rect
			(at 2.050034 7.22503 90)
			(size 0.519938 1.4986)
			(layers "F.Cu" "F.Mask" "F.Paste")
			(net "GND")
		)
		(pad "223" smd rect
			(at 2.050034 8.074914 90)
			(size 0.519938 1.4986)
			(layers "F.Cu" "F.Mask" "F.Paste")
			(net "M_A_CPU1_SB_CA<3>")
		)
		(pad "224" smd rect
			(at 2.050034 8.925052 90)
			(size 0.519938 1.4986)
			(layers "F.Cu" "F.Mask" "F.Paste")
			(net "GND")
		)
		(pad "225" smd rect
			(at 2.050034 9.774936 90)
			(size 0.519938 1.4986)
			(layers "F.Cu" "F.Mask" "F.Paste")
			(net "M_A_CPU1_SB_CA<5>")
		)
		(pad "226" smd rect
			(at 2.050034 10.625074 90)
			(size 0.519938 1.4986)
			(layers "F.Cu" "F.Mask" "F.Paste")
			(net "GND")
		)
		(pad "227" smd rect
			(at 2.050034 11.474958 90)
			(size 0.519938 1.4986)
			(layers "F.Cu" "F.Mask" "F.Paste")
			(net "M_A_CPU1_SB_PAR")
		)
		(pad "228" smd rect
			(at 2.050034 12.325096 90)
			(size 0.519938 1.4986)
			(layers "F.Cu" "F.Mask" "F.Paste")
			(net "GND")
		)
		(pad "229" smd rect
			(at 2.050034 13.17498 90)
			(size 0.519938 1.4986)
			(layers "F.Cu" "F.Mask" "F.Paste")
			(net "M_A_CPU1_SB_CS_N<1>")
		)
		(pad "230" smd rect
			(at 2.050034 14.025118 90)
			(size 0.519938 1.4986)
			(layers "F.Cu" "F.Mask" "F.Paste")
			(net "GND")
		)
	)
)
